(kicad_pcb
	(version 20221018)
	(generator pcbnew)
	(general
    (thickness 1.656)
  )
	(paper "A4")
	(title_block
    (title "SDI-MIPI Bridge")
    (date "2023-08-09")
    (rev "1.3.4")
    (company "Antmicro")
		(comment 9 "footprints 123-134 of 190")
	)
	(layers
    (0 "F.Cu" signal)
    (1 "In1.Cu" power)
    (2 "In2.Cu" power)
    (3 "In3.Cu" signal)
    (4 "In4.Cu" signal)
    (31 "B.Cu" signal)
    (32 "B.Adhes" user "B.Adhesive")
    (33 "F.Adhes" user "F.Adhesive")
    (34 "B.Paste" user)
    (35 "F.Paste" user)
    (36 "B.SilkS" user "B.Silkscreen")
    (37 "F.SilkS" user "F.Silkscreen")
    (38 "B.Mask" user)
    (39 "F.Mask" user)
    (40 "Dwgs.User" user "User.Drawings")
    (41 "Cmts.User" user "User.Comments")
    (42 "Eco1.User" user "User.Eco1")
    (43 "Eco2.User" user "User.Eco2")
    (44 "Edge.Cuts" user)
    (45 "Margin" user)
    (46 "B.CrtYd" user "B.Courtyard")
    (47 "F.CrtYd" user "F.Courtyard")
    (48 "B.Fab" user)
    (49 "F.Fab" user)
  )
	(footprint "sdi-mipi-bridge-footprints:TP_SMD_0.75mm" (layer "B.Cu")
    (at 130.9492 119.4 90)
    (property "Author" "Antmicro")
    (property "License" "Apache-2.0")
    (property "MPN" "")
    (property "Manufacturer" "")
    (property "Sheetfile" "sdi-mipi-bridge.kicad_sch")
    (property "Sheetname" "")
    (property "ki_description" "Test Point 0.75mm")
    (attr smd)
    (fp_text reference "TP10" (at -0.4 0.6508 180) (layer "B.SilkS")
        (effects (font (size 0.7 0.7) (thickness 0.15)) (justify right bottom mirror))
    )
    (fp_text value "TP_0.75mm_SMD" (at 0 -1.2 90) (layer "B.Fab") hide
        (effects (font (size 0.7 0.7) (thickness 0.15)) (justify right bottom mirror))
    )
    (fp_text user "${REFERENCE}" (at -0.4 -2.7 90) (layer "B.Fab") hide
        (effects (font (size 0.7 0.7) (thickness 0.15)) (justify right bottom mirror))
    )
    (fp_text user "Author: Antmicro" (at -0.4 -3.901 90) (layer "B.Fab") hide
        (effects (font (size 0.7 0.7) (thickness 0.15)) (justify right bottom mirror))
    )
    (fp_text user "License: Apache-2.0" (at -0.4 -5.101 90) (layer "B.Fab") hide
        (effects (font (size 0.7 0.7) (thickness 0.15)) (justify right bottom mirror))
    )
    (pad "1" smd circle (at 0 0 90) (size 0.75 0.75) (layers "B.Cu" "B.Mask")
      (net 33 "/D3") (pinfunction "1") (pintype "passive"))
  )
	(footprint "sdi-mipi-bridge-footprints:TP_SMD_0.75mm" (layer "B.Cu")
    (at 130.9492 118.4 90)
    (property "Author" "Antmicro")
    (property "License" "Apache-2.0")
    (property "MPN" "")
    (property "Manufacturer" "")
    (property "Sheetfile" "sdi-mipi-bridge.kicad_sch")
    (property "Sheetname" "")
    (property "ki_description" "Test Point 0.75mm")
    (attr smd)
    (fp_text reference "TP11" (at -0.4 0.6508 180) (layer "B.SilkS")
        (effects (font (size 0.7 0.7) (thickness 0.15)) (justify right bottom mirror))
    )
    (fp_text value "TP_0.75mm_SMD" (at 0 -1.2 90) (layer "B.Fab") hide
        (effects (font (size 0.7 0.7) (thickness 0.15)) (justify right bottom mirror))
    )
    (fp_text user "${REFERENCE}" (at -0.4 -2.7 90) (layer "B.Fab") hide
        (effects (font (size 0.7 0.7) (thickness 0.15)) (justify right bottom mirror))
    )
    (fp_text user "Author: Antmicro" (at -0.4 -3.901 90) (layer "B.Fab") hide
        (effects (font (size 0.7 0.7) (thickness 0.15)) (justify right bottom mirror))
    )
    (fp_text user "License: Apache-2.0" (at -0.4 -5.101 90) (layer "B.Fab") hide
        (effects (font (size 0.7 0.7) (thickness 0.15)) (justify right bottom mirror))
    )
    (pad "1" smd circle (at 0 0 90) (size 0.75 0.75) (layers "B.Cu" "B.Mask")
      (net 34 "/D4") (pinfunction "1") (pintype "passive"))
  )
	(footprint "sdi-mipi-bridge-footprints:TP_SMD_0.75mm" (layer "B.Cu")
    (at 130.9492 117.4 90)
    (property "Author" "Antmicro")
    (property "License" "Apache-2.0")
    (property "MPN" "")
    (property "Manufacturer" "")
    (property "Sheetfile" "sdi-mipi-bridge.kicad_sch")
    (property "Sheetname" "")
    (property "ki_description" "Test Point 0.75mm")
    (attr smd)
    (fp_text reference "TP12" (at -0.4 0.6508 180) (layer "B.SilkS")
        (effects (font (size 0.7 0.7) (thickness 0.15)) (justify right bottom mirror))
    )
    (fp_text value "TP_0.75mm_SMD" (at 0 -1.2 90) (layer "B.Fab") hide
        (effects (font (size 0.7 0.7) (thickness 0.15)) (justify right bottom mirror))
    )
    (fp_text user "${REFERENCE}" (at -0.4 -2.7 90) (layer "B.Fab") hide
        (effects (font (size 0.7 0.7) (thickness 0.15)) (justify right bottom mirror))
    )
    (fp_text user "License: Apache-2.0" (at -0.4 -5.101 90) (layer "B.Fab") hide
        (effects (font (size 0.7 0.7) (thickness 0.15)) (justify right bottom mirror))
    )
    (fp_text user "Author: Antmicro" (at -0.4 -3.901 90) (layer "B.Fab") hide
        (effects (font (size 0.7 0.7) (thickness 0.15)) (justify right bottom mirror))
    )
    (pad "1" smd circle (at 0 0 90) (size 0.75 0.75) (layers "B.Cu" "B.Mask")
      (net 35 "/D5") (pinfunction "1") (pintype "passive"))
  )
	(footprint "sdi-mipi-bridge-footprints:TP_SMD_0.75mm" (layer "B.Cu")
    (at 130.9492 116.4 90)
    (property "Author" "Antmicro")
    (property "License" "Apache-2.0")
    (property "MPN" "")
    (property "Manufacturer" "")
    (property "Sheetfile" "sdi-mipi-bridge.kicad_sch")
    (property "Sheetname" "")
    (property "ki_description" "Test Point 0.75mm")
    (attr smd)
    (fp_text reference "TP13" (at -0.4 0.6508 180) (layer "B.SilkS")
        (effects (font (size 0.7 0.7) (thickness 0.15)) (justify right bottom mirror))
    )
    (fp_text value "TP_0.75mm_SMD" (at 0 -1.2 90) (layer "B.Fab") hide
        (effects (font (size 0.7 0.7) (thickness 0.15)) (justify right bottom mirror))
    )
    (fp_text user "${REFERENCE}" (at -0.4 -2.7 90) (layer "B.Fab") hide
        (effects (font (size 0.7 0.7) (thickness 0.15)) (justify right bottom mirror))
    )
    (fp_text user "Author: Antmicro" (at -0.4 -3.901 90) (layer "B.Fab") hide
        (effects (font (size 0.7 0.7) (thickness 0.15)) (justify right bottom mirror))
    )
    (fp_text user "License: Apache-2.0" (at -0.4 -5.101 90) (layer "B.Fab") hide
        (effects (font (size 0.7 0.7) (thickness 0.15)) (justify right bottom mirror))
    )
    (pad "1" smd circle (at 0 0 90) (size 0.75 0.75) (layers "B.Cu" "B.Mask")
      (net 36 "/D6") (pinfunction "1") (pintype "passive"))
  )
	(footprint "sdi-mipi-bridge-footprints:TP_SMD_0.75mm" (layer "B.Cu")
    (at 130.9492 115.4 90)
    (property "Author" "Antmicro")
    (property "License" "Apache-2.0")
    (property "MPN" "")
    (property "Manufacturer" "")
    (property "Sheetfile" "sdi-mipi-bridge.kicad_sch")
    (property "Sheetname" "")
    (property "ki_description" "Test Point 0.75mm")
    (attr smd)
    (fp_text reference "TP14" (at -0.4 0.6508 180) (layer "B.SilkS")
        (effects (font (size 0.7 0.7) (thickness 0.15)) (justify right bottom mirror))
    )
    (fp_text value "TP_0.75mm_SMD" (at 0 -1.2 90) (layer "B.Fab") hide
        (effects (font (size 0.7 0.7) (thickness 0.15)) (justify right bottom mirror))
    )
    (fp_text user "License: Apache-2.0" (at -0.4 -5.101 90) (layer "B.Fab") hide
        (effects (font (size 0.7 0.7) (thickness 0.15)) (justify right bottom mirror))
    )
    (fp_text user "${REFERENCE}" (at -0.4 -2.7 90) (layer "B.Fab") hide
        (effects (font (size 0.7 0.7) (thickness 0.15)) (justify right bottom mirror))
    )
    (fp_text user "Author: Antmicro" (at -0.4 -3.901 90) (layer "B.Fab") hide
        (effects (font (size 0.7 0.7) (thickness 0.15)) (justify right bottom mirror))
    )
    (pad "1" smd circle (at 0 0 90) (size 0.75 0.75) (layers "B.Cu" "B.Mask")
      (net 37 "/D7") (pinfunction "1") (pintype "passive"))
  )
	(footprint "sdi-mipi-bridge-footprints:TP_SMD_0.75mm" (layer "B.Cu")
    (at 130.9492 114.4 90)
    (property "Author" "Antmicro")
    (property "License" "Apache-2.0")
    (property "MPN" "")
    (property "Manufacturer" "")
    (property "Sheetfile" "sdi-mipi-bridge.kicad_sch")
    (property "Sheetname" "")
    (property "ki_description" "Test Point 0.75mm")
    (attr smd)
    (fp_text reference "TP15" (at -0.4 0.6508 180) (layer "B.SilkS")
        (effects (font (size 0.7 0.7) (thickness 0.15)) (justify right bottom mirror))
    )
    (fp_text value "TP_0.75mm_SMD" (at 0 -1.2 90) (layer "B.Fab") hide
        (effects (font (size 0.7 0.7) (thickness 0.15)) (justify right bottom mirror))
    )
    (fp_text user "Author: Antmicro" (at -0.4 -3.901 90) (layer "B.Fab") hide
        (effects (font (size 0.7 0.7) (thickness 0.15)) (justify right bottom mirror))
    )
    (fp_text user "${REFERENCE}" (at -0.4 -2.7 90) (layer "B.Fab") hide
        (effects (font (size 0.7 0.7) (thickness 0.15)) (justify right bottom mirror))
    )
    (fp_text user "License: Apache-2.0" (at -0.4 -5.101 90) (layer "B.Fab") hide
        (effects (font (size 0.7 0.7) (thickness 0.15)) (justify right bottom mirror))
    )
    (pad "1" smd circle (at 0 0 90) (size 0.75 0.75) (layers "B.Cu" "B.Mask")
      (net 38 "/D8") (pinfunction "1") (pintype "passive"))
  )
	(footprint "sdi-mipi-bridge-footprints:TP_SMD_0.75mm" (layer "B.Cu")
    (at 130.9492 113.4 90)
    (property "Author" "Antmicro")
    (property "License" "Apache-2.0")
    (property "MPN" "")
    (property "Manufacturer" "")
    (property "Sheetfile" "sdi-mipi-bridge.kicad_sch")
    (property "Sheetname" "")
    (property "ki_description" "Test Point 0.75mm")
    (attr smd)
    (fp_text reference "TP16" (at -0.4 0.6508 180) (layer "B.SilkS")
        (effects (font (size 0.7 0.7) (thickness 0.15)) (justify right bottom mirror))
    )
    (fp_text value "TP_0.75mm_SMD" (at 0 -1.2 90) (layer "B.Fab") hide
        (effects (font (size 0.7 0.7) (thickness 0.15)) (justify right bottom mirror))
    )
    (fp_text user "Author: Antmicro" (at -0.4 -3.901 90) (layer "B.Fab") hide
        (effects (font (size 0.7 0.7) (thickness 0.15)) (justify right bottom mirror))
    )
    (fp_text user "${REFERENCE}" (at -0.4 -2.7 90) (layer "B.Fab") hide
        (effects (font (size 0.7 0.7) (thickness 0.15)) (justify right bottom mirror))
    )
    (fp_text user "License: Apache-2.0" (at -0.4 -5.101 90) (layer "B.Fab") hide
        (effects (font (size 0.7 0.7) (thickness 0.15)) (justify right bottom mirror))
    )
    (pad "1" smd circle (at 0 0 90) (size 0.75 0.75) (layers "B.Cu" "B.Mask")
      (net 39 "/D9") (pinfunction "1") (pintype "passive"))
  )
	(footprint "sdi-mipi-bridge-footprints:C_0603_1608Metric" (layer "B.Cu")
    (at 130.5 133.253 90)
    (descr "Capacitor SMD 0603")
    (tags "capacitor 0603")
    (property "Author" "Antmicro")
    (property "License" "Apache-2.0")
    (property "MPN" "GRM188R61A106KE69D")
    (property "Manufacturer" "Murata")
    (property "Sheetfile" "sdi-mipi-bridge.kicad_sch")
    (property "Sheetname" "")
    (property "Val" "10u")
    (property "Voltage" "")
    (property "ki_description" " ")
    (attr smd)
    (fp_text reference "C15" (at 1.253 0.3 90) (layer "B.SilkS")
        (effects (font (size 0.7 0.7) (thickness 0.15)) (justify right bottom mirror))
    )
    (fp_text value "C_10u_0603" (at 0 -1.6 90) (layer "B.Fab") hide
        (effects (font (size 0.7 0.7) (thickness 0.15)) (justify right bottom mirror))
    )
    (fp_text user "${REFERENCE}" (at -1.682 -3.895 90) (layer "B.Fab") hide
        (effects (font (size 0.7 0.7) (thickness 0.15)) (justify right bottom mirror))
    )
    (fp_text user "License: Apache-2.0" (at -1.682 -5.895 90) (layer "B.Fab") hide
        (effects (font (size 0.7 0.7) (thickness 0.15)) (justify right bottom mirror))
    )
    (fp_text user "Author: Antmicro" (at -1.682 -4.894 90) (layer "B.Fab") hide
        (effects (font (size 0.7 0.7) (thickness 0.15)) (justify right bottom mirror))
    )
    (fp_line (start -0.3 -0.3) (end 0.3 -0.3)
      (stroke (width 0.15) (type solid)) (layer "B.SilkS"))
    (fp_line (start -0.3 0.3) (end 0.3 0.3)
      (stroke (width 0.15) (type solid)) (layer "B.SilkS"))
    (fp_rect (start -1.24 0.7) (end 1.24 -0.7)
      (stroke (width 0.05) (type solid)) (fill none) (layer "B.CrtYd"))
    (fp_rect (start -0.8 0.4) (end 0.8 -0.4)
      (stroke (width 0.15) (type solid)) (fill none) (layer "B.Fab"))
    (pad "1" smd roundrect (at -0.7 0 90) (size 0.6 0.8) (layers "B.Cu" "B.Paste" "B.Mask") (roundrect_rratio 0.2)
      (net 1 "GNDREF") (pintype "passive"))
    (pad "2" smd roundrect (at 0.7 0 90) (size 0.6 0.8) (layers "B.Cu" "B.Paste" "B.Mask") (roundrect_rratio 0.2)
      (net 2 "+1V2") (pintype "passive"))
  )
	(footprint "sdi-mipi-bridge-footprints:C_0402_1005Metric" (layer "B.Cu")
    (at 126.1 132.53 180)
    (descr "Capacitor SMD 0402")
    (tags "capacitor SMD 0402")
    (property "Author" "Antmicro")
    (property "Dielectric" "")
    (property "License" "Apache-2.0")
    (property "MPN" "C1005X6S1A105K050BC")
    (property "Manufacturer" "TDK")
    (property "Sheetfile" "sdi-mipi-bridge.kicad_sch")
    (property "Sheetname" "")
    (property "Val" "1u")
    (property "Voltage" "")
    (property "ki_description" " ")
    (attr smd)
    (fp_text reference "C28" (at 1.301 -0.35) (layer "B.SilkS")
        (effects (font (size 0.7 0.7) (thickness 0.15)) (justify left bottom mirror))
    )
    (fp_text value "C_1u_0402" (at -100.01 -1.42) (layer "B.Fab") hide
        (effects (font (size 0.7 0.7) (thickness 0.15)) (justify left bottom mirror))
    )
    (fp_text user "License: Apache-2.0" (at -0.932 -5.17) (layer "B.Fab") hide
        (effects (font (size 0.7 0.7) (thickness 0.15)) (justify left bottom mirror))
    )
    (fp_text user "Author: Antmicro" (at -0.932 -4.17) (layer "B.Fab") hide
        (effects (font (size 0.7 0.7) (thickness 0.15)) (justify left bottom mirror))
    )
    (fp_text user "${REFERENCE}" (at -0.932 -3.168) (layer "B.Fab") hide
        (effects (font (size 0.7 0.7) (thickness 0.15)) (justify left bottom mirror))
    )
    (fp_rect (start -0.94 0.47) (end 0.94 -0.47)
      (stroke (width 0.05) (type solid)) (fill none) (layer "B.CrtYd"))
    (fp_rect (start -0.499 0.249) (end 0.499 -0.249)
      (stroke (width 0.15) (type solid)) (fill none) (layer "B.Fab"))
    (pad "1" smd roundrect (at -0.484 0 180) (size 0.59 0.64) (layers "B.Cu" "B.Paste" "B.Mask") (roundrect_rratio 0.25)
      (net 3 "GNDA") (pintype "passive"))
    (pad "2" smd roundrect (at 0.484 0 180) (size 0.59 0.64) (layers "B.Cu" "B.Paste" "B.Mask") (roundrect_rratio 0.25)
      (net 5 "+3.3VA") (pintype "passive"))
  )
	(footprint "sdi-mipi-bridge-footprints:C_0402_1005Metric" (layer "B.Cu")
    (at 126.1 133.53 180)
    (descr "Capacitor SMD 0402")
    (tags "capacitor SMD 0402")
    (property "Author" "Antmicro")
    (property "Dielectric" "")
    (property "License" "Apache-2.0")
    (property "MPN" "C1005X6S1A105K050BC")
    (property "Manufacturer" "TDK")
    (property "Sheetfile" "sdi-mipi-bridge.kicad_sch")
    (property "Sheetname" "")
    (property "Val" "1u")
    (property "Voltage" "")
    (property "ki_description" " ")
    (attr smd)
    (fp_text reference "C24" (at 1.301 -0.35) (layer "B.SilkS")
        (effects (font (size 0.7 0.7) (thickness 0.15)) (justify left bottom mirror))
    )
    (fp_text value "C_1u_0402" (at 0 -1.4) (layer "B.Fab") hide
        (effects (font (size 0.7 0.7) (thickness 0.15)) (justify left bottom mirror))
    )
    (fp_text user "License: Apache-2.0" (at -0.932 -5.17) (layer "B.Fab") hide
        (effects (font (size 0.7 0.7) (thickness 0.15)) (justify left bottom mirror))
    )
    (fp_text user "${REFERENCE}" (at -0.932 -3.168) (layer "B.Fab") hide
        (effects (font (size 0.7 0.7) (thickness 0.15)) (justify left bottom mirror))
    )
    (fp_text user "Author: Antmicro" (at -0.932 -4.17) (layer "B.Fab") hide
        (effects (font (size 0.7 0.7) (thickness 0.15)) (justify left bottom mirror))
    )
    (fp_rect (start -0.94 0.47) (end 0.94 -0.47)
      (stroke (width 0.05) (type solid)) (fill none) (layer "B.CrtYd"))
    (fp_rect (start -0.499 0.249) (end 0.499 -0.249)
      (stroke (width 0.15) (type solid)) (fill none) (layer "B.Fab"))
    (pad "1" smd roundrect (at -0.484 0 180) (size 0.59 0.64) (layers "B.Cu" "B.Paste" "B.Mask") (roundrect_rratio 0.25)
      (net 1 "GNDREF") (pintype "passive"))
    (pad "2" smd roundrect (at 0.484 0 180) (size 0.59 0.64) (layers "B.Cu" "B.Paste" "B.Mask") (roundrect_rratio 0.25)
      (net 6 "+3V3") (pintype "passive"))
  )
	(footprint "sdi-mipi-bridge-footprints:C_0402_1005Metric" (layer "B.Cu")
    (at 146.93 118.86 90)
    (descr "Capacitor SMD 0402")
    (tags "capacitor SMD 0402")
    (property "Author" "Antmicro")
    (property "Dielectric" "")
    (property "License" "Apache-2.0")
    (property "MPN" "0402X104K6R3CT")
    (property "Manufacturer" "Walsin")
    (property "Sheetfile" "sdi-mipi-bridge.kicad_sch")
    (property "Sheetname" "")
    (property "Val" "100n")
    (property "Voltage" "")
    (property "ki_description" " ")
    (attr smd)
    (fp_text reference "C39" (at -8.94 9.07 90) (layer "B.SilkS")
        (effects (font (size 0.7 0.7) (thickness 0.15)) (justify right bottom mirror))
    )
    (fp_text value "C_100n_6V3_0402" (at 0 -1.4 90) (layer "B.Fab") hide
        (effects (font (size 0.7 0.7) (thickness 0.15)) (justify right bottom mirror))
    )
    (fp_text user "${REFERENCE}" (at -0.932 -3.168 90) (layer "B.Fab") hide
        (effects (font (size 0.7 0.7) (thickness 0.15)) (justify right bottom mirror))
    )
    (fp_text user "Author: Antmicro" (at -0.932 -4.17 90) (layer "B.Fab") hide
        (effects (font (size 0.7 0.7) (thickness 0.15)) (justify right bottom mirror))
    )
    (fp_text user "License: Apache-2.0" (at -0.932 -5.17 90) (layer "B.Fab") hide
        (effects (font (size 0.7 0.7) (thickness 0.15)) (justify right bottom mirror))
    )
    (fp_rect (start -0.94 0.47) (end 0.94 -0.47)
      (stroke (width 0.05) (type solid)) (fill none) (layer "B.CrtYd"))
    (fp_rect (start -0.499 0.249) (end 0.499 -0.249)
      (stroke (width 0.15) (type solid)) (fill none) (layer "B.Fab"))
    (pad "1" smd roundrect (at -0.484 0 90) (size 0.59 0.64) (layers "B.Cu" "B.Paste" "B.Mask") (roundrect_rratio 0.25)
      (net 1 "GNDREF") (pintype "passive"))
    (pad "2" smd roundrect (at 0.484 0 90) (size 0.59 0.64) (layers "B.Cu" "B.Paste" "B.Mask") (roundrect_rratio 0.25)
      (net 2 "+1V2") (pintype "passive"))
  )
	(footprint "sdi-mipi-bridge-footprints:C_0402_1005Metric" (layer "B.Cu")
    (at 145.255 114.96 180)
    (descr "Capacitor SMD 0402")
    (tags "capacitor SMD 0402")
    (property "Author" "Antmicro")
    (property "Dielectric" "")
    (property "License" "Apache-2.0")
    (property "MPN" "0402X104K6R3CT")
    (property "Manufacturer" "Walsin")
    (property "Sheetfile" "sdi-mipi-bridge.kicad_sch")
    (property "Sheetname" "")
    (property "Val" "100n")
    (property "Voltage" "")
    (property "ki_description" " ")
    (attr smd)
    (fp_text reference "C50" (at -9.745 -8.24) (layer "B.SilkS")
        (effects (font (size 0.7 0.7) (thickness 0.15)) (justify left bottom mirror))
    )
    (fp_text value "C_100n_6V3_0402" (at 0 -1.4) (layer "B.Fab") hide
        (effects (font (size 0.7 0.7) (thickness 0.15)) (justify left bottom mirror))
    )
    (fp_text user "License: Apache-2.0" (at -0.932 -5.17) (layer "B.Fab") hide
        (effects (font (size 0.7 0.7) (thickness 0.15)) (justify left bottom mirror))
    )
    (fp_text user "${REFERENCE}" (at -0.932 -3.168) (layer "B.Fab") hide
        (effects (font (size 0.7 0.7) (thickness 0.15)) (justify left bottom mirror))
    )
    (fp_text user "Author: Antmicro" (at -0.932 -4.17) (layer "B.Fab") hide
        (effects (font (size 0.7 0.7) (thickness 0.15)) (justify left bottom mirror))
    )
    (fp_rect (start -0.94 0.47) (end 0.94 -0.47)
      (stroke (width 0.05) (type solid)) (fill none) (layer "B.CrtYd"))
    (fp_rect (start -0.499 0.249) (end 0.499 -0.249)
      (stroke (width 0.15) (type solid)) (fill none) (layer "B.Fab"))
    (pad "1" smd roundrect (at -0.484 0 180) (size 0.59 0.64) (layers "B.Cu" "B.Paste" "B.Mask") (roundrect_rratio 0.25)
      (net 1 "GNDREF") (pintype "passive"))
    (pad "2" smd roundrect (at 0.484 0 180) (size 0.59 0.64) (layers "B.Cu" "B.Paste" "B.Mask") (roundrect_rratio 0.25)
      (net 79 "VCC_IO") (pintype "passive"))
  )
)
